(kicad_pcb
	(version 20260206)
	(generator "pcbnew")
	(generator_version "10.0")
	(general
		(thickness 1.6)
		(legacy_teardrops no)
	)
	(paper "A4")
	(title_block
		(title "01162023_DA0F0TEBIF0_F0T_Expander_BD_F_brd_V02_OCP.brd")
		(comment 1 "Grand Teton / footprint 1840 of 9728 (U6), pads 111-220 of 484")
	)
	(layers
		(0 "F.Cu" signal "TOP")
		(4 "In1.Cu" signal "GND")
		(6 "In2.Cu" signal "VCC")
		(8 "In3.Cu" signal "VCC1")
		(10 "In4.Cu" signal "GND1")
		(12 "In5.Cu" signal "IN1")
		(14 "In6.Cu" signal "GND2")
		(16 "In7.Cu" signal "IN2")
		(18 "In8.Cu" signal "GND3")
		(20 "In9.Cu" signal "IN3")
		(22 "In10.Cu" signal "GND4")
		(24 "In11.Cu" signal "IN4")
		(26 "In12.Cu" signal "GND5")
		(28 "In13.Cu" signal "IN5")
		(30 "In14.Cu" signal "GND6")
		(32 "In15.Cu" signal "IN6")
		(34 "In16.Cu" signal "GND7")
		(2 "B.Cu" signal "BOTTOM")
		(9 "F.Adhes" user "F.Adhesive")
		(11 "B.Adhes" user "B.Adhesive")
		(13 "F.Paste" user "Package Geometry/Pastemask Top")
		(15 "B.Paste" user "Package Geometry/Pastemask Bottom")
		(5 "F.SilkS" user "Ref Des/Silkscreen Top")
		(7 "B.SilkS" user "Ref Des/Silkscreen Bottom")
		(1 "F.Mask" user "Board Geometry/Soldermask Top")
		(3 "B.Mask" user "Board Geometry/Soldermask Bottom")
		(17 "Dwgs.User" user "User.Drawings")
		(19 "Cmts.User" user "User.Comments")
		(21 "Eco1.User" user "User.Eco1")
		(23 "Eco2.User" user "User.Eco2")
		(25 "Edge.Cuts" user "Board Geometry/Outline")
		(27 "Margin" user)
		(31 "F.CrtYd" user "Package Geometry/Place Bound Top")
		(29 "B.CrtYd" user "Package Geometry/Place Bound Bottom")
		(35 "F.Fab" user "Ref Des/Assembly Top")
		(33 "B.Fab" user "Ref Des/Assembly Bottom")
	)
	(footprint ""
		(layer "F.Cu")
		(at 342.493854 -219.587064)
		(property "Reference" "U6"
			(at -10.3632 -10.963148 0)
			(unlocked yes)
			(layer "F.SilkS")
			(effects
				(font
					(size 0.7874 0.5842)
					(thickness 0.1524)
				)
				(justify left)
			)
		)
		(property "Value" ""
			(at 0 0 0)
			(layer "F.Fab")
			(effects
				(font
					(size 1.27 1.27)
				)
			)
		)
		(duplicate_pad_numbers_are_jumpers no)
		(pad "D1" smd circle
			(at -8.400034 -5.999988)
			(size 0.4064 0.4064)
			(layers "F.Cu" "F.Mask" "F.Paste")
			(net "PWRGD_P1V25_PEX3_R")
		)
		(pad "D2" smd circle
			(at -7.599934 -5.999988)
			(size 0.4064 0.4064)
			(layers "F.Cu" "F.Mask" "F.Paste")
			(net "PWRGD_P1V25_PEX0_R")
		)
		(pad "D3" smd circle
			(at -6.800088 -5.999988)
			(size 0.4064 0.4064)
			(layers "F.Cu" "F.Mask" "F.Paste")
			(net "PWRGD_P12V_AUX_BUF_R")
		)
		(pad "D4" smd circle
			(at -5.999988 -5.999988)
			(size 0.4064 0.4064)
			(layers "F.Cu" "F.Mask" "F.Paste")
			(net "PWRGD_P5V_AUX_BUF_R")
		)
		(pad "D5" smd circle
			(at -5.199888 -5.999988)
			(size 0.4064 0.4064)
			(layers "F.Cu" "F.Mask" "F.Paste")
			(net "RST_SSD2_PERST_N")
		)
		(pad "D6" smd circle
			(at -4.400042 -5.999988)
			(size 0.4064 0.4064)
			(layers "F.Cu" "F.Mask" "F.Paste")
			(net "JP_FPGA_FRC_PWRON_N")
		)
		(pad "D7" smd circle
			(at -3.599942 -5.999988)
			(size 0.4064 0.4064)
			(layers "F.Cu" "F.Mask" "F.Paste")
			(net "SMB_PEX0_FPGA_SDA")
		)
		(pad "D8" smd circle
			(at -2.800096 -5.999988)
			(size 0.4064 0.4064)
			(layers "F.Cu" "F.Mask" "F.Paste")
			(net "SMB_PEX1_FPGA_SDA")
		)
		(pad "D9" smd circle
			(at -1.999996 -5.999988)
			(size 0.4064 0.4064)
			(layers "F.Cu" "F.Mask" "F.Paste")
			(net "SMB_PEX3_FPGA_SDA")
		)
		(pad "D10" smd circle
			(at -1.199896 -5.999988)
			(size 0.4064 0.4064)
			(layers "F.Cu" "F.Mask" "F.Paste")
			(net "JTAG_FPGA_TCK")
		)
		(pad "D11" smd circle
			(at -0.40005 -5.999988)
			(size 0.4064 0.4064)
			(layers "F.Cu" "F.Mask" "F.Paste")
			(net "SSD1_CLK_EN_N")
		)
		(pad "D12" smd circle
			(at 0.40005 -5.999988)
			(size 0.4064 0.4064)
			(layers "F.Cu" "F.Mask" "F.Paste")
			(net "SMB_MB_BMC_ISO_FPGA_SCL")
		)
		(pad "D13" smd circle
			(at 1.199896 -5.999988)
			(size 0.4064 0.4064)
			(layers "F.Cu" "F.Mask" "F.Paste")
			(net "SSD3_PWRDIS")
		)
		(pad "D14" smd circle
			(at 1.999996 -5.999988)
			(size 0.4064 0.4064)
			(layers "F.Cu" "F.Mask" "F.Paste")
			(net "PWRGD_P12V_SSD4_R")
		)
		(pad "D15" smd circle
			(at 2.800096 -5.999988)
			(size 0.4064 0.4064)
			(layers "F.Cu" "F.Mask" "F.Paste")
			(net "PRSNT_SSD5_R_N")
		)
		(pad "D16" smd circle
			(at 3.599942 -5.999988)
			(size 0.4064 0.4064)
			(layers "F.Cu" "F.Mask" "F.Paste")
			(net "SSD5_PWRDIS")
		)
		(pad "D17" smd circle
			(at 4.400042 -5.999988)
			(size 0.4064 0.4064)
			(layers "F.Cu" "F.Mask" "F.Paste")
			(net "PWRGD_P12V_SSD6_R")
		)
		(pad "D18" smd circle
			(at 5.199888 -5.999988)
			(size 0.4064 0.4064)
			(layers "F.Cu" "F.Mask" "F.Paste")
			(net "RST_SSD6_PERST_N")
		)
		(pad "D19" smd circle
			(at 5.999988 -5.999988)
			(size 0.4064 0.4064)
			(layers "F.Cu" "F.Mask" "F.Paste")
			(net "RST_NIC0_PERST_N")
		)
		(pad "D20" smd circle
			(at 6.800088 -5.999988)
			(size 0.4064 0.4064)
			(layers "F.Cu" "F.Mask" "F.Paste")
			(net "NIC0_CLK_EN_N")
		)
		(pad "D21" smd circle
			(at 7.599934 -5.999988)
			(size 0.4064 0.4064)
			(layers "F.Cu" "F.Mask" "F.Paste")
			(net "NIC0_MAIN_PWR_EN")
		)
		(pad "D22" smd circle
			(at 8.400034 -5.999988)
			(size 0.4064 0.4064)
			(layers "F.Cu" "F.Mask" "F.Paste")
			(net "PWRGD_NIC0_PWR_GOOD_R")
		)
		(pad "E1" smd circle
			(at -8.400034 -5.199888)
			(size 0.4064 0.4064)
			(layers "F.Cu" "F.Mask" "F.Paste")
			(net "PWR_EN_PEX")
		)
		(pad "E2" smd circle
			(at -7.599934 -5.199888)
			(size 0.4064 0.4064)
			(layers "F.Cu" "F.Mask" "F.Paste")
			(net "PWRGD_P1V8_PEX_R")
		)
		(pad "E3" smd circle
			(at -6.800088 -5.199888)
			(size 0.4064 0.4064)
			(layers "F.Cu" "F.Mask" "F.Paste")
			(net "PWR_EN_P1V2_AUX")
		)
		(pad "E4" smd circle
			(at -5.999988 -5.199888)
			(size 0.4064 0.4064)
			(layers "F.Cu" "F.Mask" "F.Paste")
			(net "PWRGD_P3V3_R")
		)
		(pad "E5" smd circle
			(at -5.199888 -5.199888)
			(size 0.4064 0.4064)
			(layers "F.Cu" "F.Mask" "F.Paste")
			(net "GND")
		)
		(pad "E6" smd circle
			(at -4.400042 -5.199888)
			(size 0.4064 0.4064)
			(layers "F.Cu" "F.Mask" "F.Paste")
			(net "RST_MB_PERST_2_ISO_R_N")
		)
		(pad "E7" smd circle
			(at -3.599942 -5.199888)
			(size 0.4064 0.4064)
			(layers "F.Cu" "F.Mask" "F.Paste")
			(net "JP_FPGA_LED")
		)
		(pad "E8" smd circle
			(at -2.800096 -5.199888)
			(size 0.4064 0.4064)
			(layers "F.Cu" "F.Mask" "F.Paste")
			(net "JTAG_FPGA_R_TDO")
		)
		(pad "E9" smd circle
			(at -1.999996 -5.199888)
			(size 0.4064 0.4064)
			(layers "F.Cu" "F.Mask" "F.Paste")
			(net "JTAG_FPGA_TDI")
		)
		(pad "E10" smd circle
			(at -1.199896 -5.199888)
			(size 0.4064 0.4064)
			(layers "F.Cu" "F.Mask" "F.Paste")
			(net "RST_SSD0_PERST_N")
		)
		(pad "E11" smd circle
			(at -0.40005 -5.199888)
			(size 0.4064 0.4064)
			(layers "F.Cu" "F.Mask" "F.Paste")
			(net "RST_SSD1_PERST_N")
		)
		(pad "E12" smd circle
			(at 0.40005 -5.199888)
			(size 0.4064 0.4064)
			(layers "F.Cu" "F.Mask" "F.Paste")
			(net "SMB_MB_BMC_ISO_FPGA_SDA")
		)
		(pad "E13" smd circle
			(at 1.199896 -5.199888)
			(size 0.4064 0.4064)
			(layers "F.Cu" "F.Mask" "F.Paste")
			(net "Net_404")
		)
		(pad "E14" smd circle
			(at 1.999996 -5.199888)
			(size 0.4064 0.4064)
			(layers "F.Cu" "F.Mask" "F.Paste")
			(net "FPGA_JTAGENB")
		)
		(pad "E15" smd circle
			(at 2.800096 -5.199888)
			(size 0.4064 0.4064)
			(layers "F.Cu" "F.Mask" "F.Paste")
			(net "PU_FPGA_PROGRAMN")
		)
		(pad "E16" smd circle
			(at 3.599942 -5.199888)
			(size 0.4064 0.4064)
			(layers "F.Cu" "F.Mask" "F.Paste")
			(net "PRSNT_SSD6_R_N")
		)
		(pad "E17" smd circle
			(at 4.400042 -5.199888)
			(size 0.4064 0.4064)
			(layers "F.Cu" "F.Mask" "F.Paste")
			(net "TP_DONE")
		)
		(pad "E18" smd circle
			(at 5.199888 -5.199888)
			(size 0.4064 0.4064)
			(layers "F.Cu" "F.Mask" "F.Paste")
			(net "GND")
		)
		(pad "E19" smd circle
			(at 5.999988 -5.199888)
			(size 0.4064 0.4064)
			(layers "F.Cu" "F.Mask" "F.Paste")
			(net "PWRGD_P3V3_NIC1_R")
		)
		(pad "E20" smd circle
			(at 6.800088 -5.199888)
			(size 0.4064 0.4064)
			(layers "F.Cu" "F.Mask" "F.Paste")
			(net "NIC1_AUX_PWR_EN")
		)
		(pad "E21" smd circle
			(at 7.599934 -5.199888)
			(size 0.4064 0.4064)
			(layers "F.Cu" "F.Mask" "F.Paste")
			(net "PWRGD_P12V_NIC1_R")
		)
		(pad "E22" smd circle
			(at 8.400034 -5.199888)
			(size 0.4064 0.4064)
			(layers "F.Cu" "F.Mask" "F.Paste")
			(net "PRSNT_NIC1_R_N")
		)
		(pad "F1" smd circle
			(at -8.400034 -4.400042)
			(size 0.4064 0.4064)
			(layers "F.Cu" "F.Mask" "F.Paste")
			(net "FM_CLK_EN")
		)
		(pad "F2" smd circle
			(at -7.599934 -4.400042)
			(size 0.4064 0.4064)
			(layers "F.Cu" "F.Mask" "F.Paste")
			(net "GND")
		)
		(pad "F3" smd circle
			(at -6.800088 -4.400042)
			(size 0.4064 0.4064)
			(layers "F.Cu" "F.Mask" "F.Paste")
			(net "P3V3_FPGA_VCCIO5")
		)
		(pad "F4" smd circle
			(at -5.999988 -4.400042)
			(size 0.4064 0.4064)
			(layers "F.Cu" "F.Mask" "F.Paste")
			(net "PWR_EN_P3V3")
		)
		(pad "F5" smd circle
			(at -5.199888 -4.400042)
			(size 0.4064 0.4064)
			(layers "F.Cu" "F.Mask" "F.Paste")
			(net "PWRGD_P0V8_PEX0_R")
		)
		(pad "F6" smd circle
			(at -4.400042 -4.400042)
			(size 0.4064 0.4064)
			(layers "F.Cu" "F.Mask" "F.Paste")
			(net "PWRGD_P3V3_AUX_BUF_R")
		)
		(pad "F7" smd circle
			(at -3.599942 -4.400042)
			(size 0.4064 0.4064)
			(layers "F.Cu" "F.Mask" "F.Paste")
			(net "MB_SWB_PWR_EN_ISO_R")
		)
		(pad "F8" smd circle
			(at -2.800096 -4.400042)
			(size 0.4064 0.4064)
			(layers "F.Cu" "F.Mask" "F.Paste")
			(net "PWRGD_P12V_SSD2_R")
		)
		(pad "F9" smd circle
			(at -1.999996 -4.400042)
			(size 0.4064 0.4064)
			(layers "F.Cu" "F.Mask" "F.Paste")
			(net "PWRGD_P3V3_SSD0_R")
		)
		(pad "F10" smd circle
			(at -1.199896 -4.400042)
			(size 0.4064 0.4064)
			(layers "F.Cu" "F.Mask" "F.Paste")
			(net "SSD0_PWRDIS")
		)
		(pad "F11" smd circle
			(at -0.40005 -4.400042)
			(size 0.4064 0.4064)
			(layers "F.Cu" "F.Mask" "F.Paste")
			(net "PWRGD_P3V3_SSD1_R")
		)
		(pad "F12" smd circle
			(at 0.40005 -4.400042)
			(size 0.4064 0.4064)
			(layers "F.Cu" "F.Mask" "F.Paste")
			(net "BIC_SYS_READY_R2_N")
		)
		(pad "F13" smd circle
			(at 1.199896 -4.400042)
			(size 0.4064 0.4064)
			(layers "F.Cu" "F.Mask" "F.Paste")
			(net "PRSNT_SSD3_R_N")
		)
		(pad "F14" smd circle
			(at 1.999996 -4.400042)
			(size 0.4064 0.4064)
			(layers "F.Cu" "F.Mask" "F.Paste")
			(net "SSD4_PWR_EN")
		)
		(pad "F15" smd circle
			(at 2.800096 -4.400042)
			(size 0.4064 0.4064)
			(layers "F.Cu" "F.Mask" "F.Paste")
			(net "PWRGD_P12V_SSD7_R")
		)
		(pad "F16" smd circle
			(at 3.599942 -4.400042)
			(size 0.4064 0.4064)
			(layers "F.Cu" "F.Mask" "F.Paste")
			(net "TP_INITN")
		)
		(pad "F17" smd circle
			(at 4.400042 -4.400042)
			(size 0.4064 0.4064)
			(layers "F.Cu" "F.Mask" "F.Paste")
			(net "PWRGD_P3V3_NIC0_R")
		)
		(pad "F18" smd circle
			(at 5.199888 -4.400042)
			(size 0.4064 0.4064)
			(layers "F.Cu" "F.Mask" "F.Paste")
			(net "RST_NIC1_PERST_N")
		)
		(pad "F19" smd circle
			(at 5.999988 -4.400042)
			(size 0.4064 0.4064)
			(layers "F.Cu" "F.Mask" "F.Paste")
			(net "NIC1_CLK_EN_N")
		)
		(pad "F20" smd circle
			(at 6.800088 -4.400042)
			(size 0.4064 0.4064)
			(layers "F.Cu" "F.Mask" "F.Paste")
			(net "P3V3_FPGA_VCCIO1")
		)
		(pad "F21" smd circle
			(at 7.599934 -4.400042)
			(size 0.4064 0.4064)
			(layers "F.Cu" "F.Mask" "F.Paste")
			(net "GND")
		)
		(pad "F22" smd circle
			(at 8.400034 -4.400042)
			(size 0.4064 0.4064)
			(layers "F.Cu" "F.Mask" "F.Paste")
			(net "PWRGD_NIC1_PWR_GOOD_R")
		)
		(pad "G1" smd circle
			(at -8.400034 -3.599942)
			(size 0.4064 0.4064)
			(layers "F.Cu" "F.Mask" "F.Paste")
			(net "RST_PEX1_PERST_N")
		)
		(pad "G2" smd circle
			(at -7.599934 -3.599942)
			(size 0.4064 0.4064)
			(layers "F.Cu" "F.Mask" "F.Paste")
			(net "RST_PEX0_PERST_N")
		)
		(pad "G3" smd circle
			(at -6.800088 -3.599942)
			(size 0.4064 0.4064)
			(layers "F.Cu" "F.Mask" "F.Paste")
			(net "RST_PEX_SYS_N")
		)
		(pad "G4" smd circle
			(at -5.999988 -3.599942)
			(size 0.4064 0.4064)
			(layers "F.Cu" "F.Mask" "F.Paste")
			(net "FM_SYS_THROTTLE")
		)
		(pad "G5" smd circle
			(at -5.199888 -3.599942)
			(size 0.4064 0.4064)
			(layers "F.Cu" "F.Mask" "F.Paste")
			(net "PWRGD_P1V25_PEX1_R")
		)
		(pad "G6" smd circle
			(at -4.400042 -3.599942)
			(size 0.4064 0.4064)
			(layers "F.Cu" "F.Mask" "F.Paste")
			(net "PWRGD_P0V8_PEX1_R")
		)
		(pad "G7" smd circle
			(at -3.599942 -3.599942)
			(size 0.4064 0.4064)
			(layers "F.Cu" "F.Mask" "F.Paste")
			(net "PWRGD_P1V2_AUX_R")
		)
		(pad "G8" smd circle
			(at -2.800096 -3.599942)
			(size 0.4064 0.4064)
			(layers "F.Cu" "F.Mask" "F.Paste")
			(net "PWRGD_P3V3_SSD2_R")
		)
		(pad "G9" smd circle
			(at -1.999996 -3.599942)
			(size 0.4064 0.4064)
			(layers "F.Cu" "F.Mask" "F.Paste")
			(net "SSD0_PWR_EN")
		)
		(pad "G10" smd circle
			(at -1.199896 -3.599942)
			(size 0.4064 0.4064)
			(layers "F.Cu" "F.Mask" "F.Paste")
			(net "P3V3_FPGA_VCCIO0")
		)
		(pad "G11" smd circle
			(at -0.40005 -3.599942)
			(size 0.4064 0.4064)
			(layers "F.Cu" "F.Mask" "F.Paste")
			(net "PWRGD_P12V_SSD1_R")
		)
		(pad "G12" smd circle
			(at 0.40005 -3.599942)
			(size 0.4064 0.4064)
			(layers "F.Cu" "F.Mask" "F.Paste")
			(net "SMB_FPGA_ALERT_N")
		)
		(pad "G13" smd circle
			(at 1.199896 -3.599942)
			(size 0.4064 0.4064)
			(layers "F.Cu" "F.Mask" "F.Paste")
			(net "P3V3_FPGA_VCCIO0")
		)
		(pad "G14" smd circle
			(at 1.999996 -3.599942)
			(size 0.4064 0.4064)
			(layers "F.Cu" "F.Mask" "F.Paste")
			(net "PWRGD_P3V3_SSD4_R")
		)
		(pad "G15" smd circle
			(at 2.800096 -3.599942)
			(size 0.4064 0.4064)
			(layers "F.Cu" "F.Mask" "F.Paste")
			(net "PWRGD_P3V3_SSD7_R")
		)
		(pad "G16" smd circle
			(at 3.599942 -3.599942)
			(size 0.4064 0.4064)
			(layers "F.Cu" "F.Mask" "F.Paste")
			(net "NIC0_AUX_PWR_EN")
		)
		(pad "G17" smd circle
			(at 4.400042 -3.599942)
			(size 0.4064 0.4064)
			(layers "F.Cu" "F.Mask" "F.Paste")
			(net "RST_NIC2_PERST_N")
		)
		(pad "G18" smd circle
			(at 5.199888 -3.599942)
			(size 0.4064 0.4064)
			(layers "F.Cu" "F.Mask" "F.Paste")
			(net "NIC2_AUX_PWR_EN")
		)
		(pad "G19" smd circle
			(at 5.999988 -3.599942)
			(size 0.4064 0.4064)
			(layers "F.Cu" "F.Mask" "F.Paste")
			(net "PWRGD_P3V3_NIC2_R")
		)
		(pad "G20" smd circle
			(at 6.800088 -3.599942)
			(size 0.4064 0.4064)
			(layers "F.Cu" "F.Mask" "F.Paste")
			(net "PWRGD_P12V_NIC2_R")
		)
		(pad "G21" smd circle
			(at 7.599934 -3.599942)
			(size 0.4064 0.4064)
			(layers "F.Cu" "F.Mask" "F.Paste")
			(net "PRSNT_NIC2_R_N")
		)
		(pad "G22" smd circle
			(at 8.400034 -3.599942)
			(size 0.4064 0.4064)
			(layers "F.Cu" "F.Mask" "F.Paste")
			(net "NIC1_MAIN_PWR_EN")
		)
		(pad "H1" smd circle
			(at -8.400034 -2.800096)
			(size 0.4064 0.4064)
			(layers "F.Cu" "F.Mask" "F.Paste")
			(net "PEX1_SYS_ERR_FPGA")
		)
		(pad "H2" smd circle
			(at -7.599934 -2.800096)
			(size 0.4064 0.4064)
			(layers "F.Cu" "F.Mask" "F.Paste")
			(net "PEX0_SYS_ERR_FPGA")
		)
		(pad "H3" smd circle
			(at -6.800088 -2.800096)
			(size 0.4064 0.4064)
			(layers "F.Cu" "F.Mask" "F.Paste")
			(net "RST_PEX3_PERST_N")
		)
		(pad "H4" smd circle
			(at -5.999988 -2.800096)
			(size 0.4064 0.4064)
			(layers "F.Cu" "F.Mask" "F.Paste")
			(net "RST_PEX2_PERST_N")
		)
		(pad "H5" smd circle
			(at -5.199888 -2.800096)
			(size 0.4064 0.4064)
			(layers "F.Cu" "F.Mask" "F.Paste")
			(net "LED_POSTCODE_0")
		)
		(pad "H6" smd circle
			(at -4.400042 -2.800096)
			(size 0.4064 0.4064)
			(layers "F.Cu" "F.Mask" "F.Paste")
			(net "PWRGD_P1V25_PEX2_R")
		)
		(pad "H7" smd circle
			(at -3.599942 -2.800096)
			(size 0.4064 0.4064)
			(layers "F.Cu" "F.Mask" "F.Paste")
			(net "PWRGD_P0V8_PEX2_R")
		)
		(pad "H8" smd circle
			(at -2.800096 -2.800096)
			(size 0.4064 0.4064)
			(layers "F.Cu" "F.Mask" "F.Paste")
			(net "GND")
		)
		(pad "H9" smd circle
			(at -1.999996 -2.800096)
			(size 0.4064 0.4064)
			(layers "F.Cu" "F.Mask" "F.Paste")
			(net "P3V3_FPGA_VCCIO0")
		)
		(pad "H10" smd circle
			(at -1.199896 -2.800096)
			(size 0.4064 0.4064)
			(layers "F.Cu" "F.Mask" "F.Paste")
			(net "GND")
		)
		(pad "H11" smd circle
			(at -0.40005 -2.800096)
			(size 0.4064 0.4064)
			(layers "F.Cu" "F.Mask" "F.Paste")
			(net "P3V3_FPGA_VCCIO0")
		)
		(pad "H12" smd circle
			(at 0.40005 -2.800096)
			(size 0.4064 0.4064)
			(layers "F.Cu" "F.Mask" "F.Paste")
			(net "P3V3_FPGA_VCCIO0")
		)
		(pad "H13" smd circle
			(at 1.199896 -2.800096)
			(size 0.4064 0.4064)
			(layers "F.Cu" "F.Mask" "F.Paste")
			(net "GND")
		)
		(pad "H14" smd circle
			(at 1.999996 -2.800096)
			(size 0.4064 0.4064)
			(layers "F.Cu" "F.Mask" "F.Paste")
			(net "P3V3_FPGA_VCCIO0")
		)
		(pad "H15" smd circle
			(at 2.800096 -2.800096)
			(size 0.4064 0.4064)
			(layers "F.Cu" "F.Mask" "F.Paste")
			(net "GND")
		)
		(pad "H16" smd circle
			(at 3.599942 -2.800096)
			(size 0.4064 0.4064)
			(layers "F.Cu" "F.Mask" "F.Paste")
			(net "NIC3_AUX_PWR_EN")
		)
		(pad "H17" smd circle
			(at 4.400042 -2.800096)
			(size 0.4064 0.4064)
			(layers "F.Cu" "F.Mask" "F.Paste")
			(net "PWRGD_P3V3_NIC3_R")
		)
		(pad "H18" smd circle
			(at 5.199888 -2.800096)
			(size 0.4064 0.4064)
			(layers "F.Cu" "F.Mask" "F.Paste")
			(net "PWRGD_P12V_NIC3_R")
		)
		(pad "H19" smd circle
			(at 5.999988 -2.800096)
			(size 0.4064 0.4064)
			(layers "F.Cu" "F.Mask" "F.Paste")
			(net "PRSNT_NIC3_R_N")
		)
		(pad "H20" smd circle
			(at 6.800088 -2.800096)
			(size 0.4064 0.4064)
			(layers "F.Cu" "F.Mask" "F.Paste")
			(net "NIC2_CLK_EN_N")
		)
		(pad "H21" smd circle
			(at 7.599934 -2.800096)
			(size 0.4064 0.4064)
			(layers "F.Cu" "F.Mask" "F.Paste")
			(net "NIC2_MAIN_PWR_EN")
		)
		(pad "H22" smd circle
			(at 8.400034 -2.800096)
			(size 0.4064 0.4064)
			(layers "F.Cu" "F.Mask" "F.Paste")
			(net "PWRGD_NIC2_PWR_GOOD_R")
		)
	)
)
